# S9S_MB_2U (Grand Teton) — schematic netlist excerpt (pin names and nets, part order shuffled) for the footprints in the layout excerpt that follows; sources: Cadence DE-HDL packaged netlist, KiCad conversion of 03242023_DA0F0TMBIJ0_F0T_Motherboard_J_brd_V01_OCP.brd

R675  Q_RES  33.2 1% CHIP  pkg 0402LF  page 230 : A = I3C_SPD_DDRABCD_CPU1_LVC1_R_SDA ; B = I3C_SPD_DDRABCD_CPU1_LVC1_SDA
C217  Q_CAP  47UF 4V 20% X6S  pkg C0805  page 74 : A = PVCCIN_CPU0 ; B = GND
C145  Q_CAP_DIFFBUS  DIFF BUS_0.22UF 6.3V 20% X6S  pkg C0201  page 178 : \1\ = DMI_CPU0_PCH_TX_C_DN<4> ; \2\ = DMI_CPU0_PCH_TX_DN<4>

(kicad_pcb
	(version 20260206)
	(generator "pcbnew")
	(generator_version "10.0")
	(general
		(thickness 1.6)
		(legacy_teardrops no)
	)
	(paper "A4")
	(title_block
		(title "03242023_DA0F0TMBIJ0_F0T_Motherboard_J_brd_V01_OCP.brd")
		(comment 1 "Grand Teton / footprints 359-361 of 6105")
	)
	(layers
		(0 "F.Cu" signal "TOP")
		(4 "In1.Cu" signal "GND")
		(6 "In2.Cu" signal "IN1")
		(8 "In3.Cu" signal "GND1")
		(10 "In4.Cu" signal "IN2")
		(12 "In5.Cu" signal "GND2")
		(14 "In6.Cu" signal "IN3")
		(16 "In7.Cu" signal "GND3")
		(18 "In8.Cu" signal "VCC")
		(20 "In9.Cu" signal "VCC1")
		(22 "In10.Cu" signal "GND4")
		(24 "In11.Cu" signal "IN4")
		(26 "In12.Cu" signal "GND5")
		(28 "In13.Cu" signal "IN5")
		(30 "In14.Cu" signal "GND6")
		(32 "In15.Cu" signal "IN6")
		(34 "In16.Cu" signal "GND7")
		(2 "B.Cu" signal "BOTTOM")
		(9 "F.Adhes" user "F.Adhesive")
		(11 "B.Adhes" user "B.Adhesive")
		(13 "F.Paste" user "Package Geometry/Pastemask Top")
		(15 "B.Paste" user "Package Geometry/Pastemask Bottom")
		(5 "F.SilkS" user "Ref Des/Silkscreen Top")
		(7 "B.SilkS" user "Ref Des/Silkscreen Bottom")
		(1 "F.Mask" user "Board Geometry/Soldermask Top")
		(3 "B.Mask" user "Board Geometry/Soldermask Bottom")
		(17 "Dwgs.User" user "User.Drawings")
		(19 "Cmts.User" user "User.Comments")
		(21 "Eco1.User" user "User.Eco1")
		(23 "Eco2.User" user "User.Eco2")
		(25 "Edge.Cuts" user "Board Geometry/Outline")
		(27 "Margin" user)
		(31 "F.CrtYd" user "Package Geometry/Place Bound Top")
		(29 "B.CrtYd" user "Package Geometry/Place Bound Bottom")
		(35 "F.Fab" user "Ref Des/Assembly Top")
		(33 "B.Fab" user "Ref Des/Assembly Bottom")
	)
	(footprint ""
		(layer "F.Cu")
		(at 356.54488 -294.01008)
		(property "Reference" "C217"
			(at 0 0 0)
			(layer "F.SilkS")
			(hide yes)
			(effects
				(font
					(size 1.27 1.27)
				)
			)
		)
		(property "Value" ""
			(at 0 0 0)
			(layer "F.Fab")
			(effects
				(font
					(size 1.27 1.27)
				)
			)
		)
		(duplicate_pad_numbers_are_jumpers no)
		(fp_line
			(start -1.524 -0.762)
			(end 1.524 -0.762)
			(stroke
				(width 0.1524)
				(type default)
			)
			(layer "F.SilkS")
		)
		(fp_line
			(start -1.524 0.762)
			(end -1.524 -0.762)
			(stroke
				(width 0.1524)
				(type default)
			)
			(layer "F.SilkS")
		)
		(fp_line
			(start 1.524 -0.762)
			(end 1.524 0.762)
			(stroke
				(width 0.1524)
				(type default)
			)
			(layer "F.SilkS")
		)
		(fp_line
			(start 1.524 0.762)
			(end -1.524 0.762)
			(stroke
				(width 0.1524)
				(type default)
			)
			(layer "F.SilkS")
		)
		(fp_line
			(start -1.1049 -0.724916)
			(end -1.1049 0.724916)
			(stroke
				(width 0.1)
				(type default)
			)
			(layer "F.Fab")
		)
		(fp_line
			(start -1.1049 0.724916)
			(end 1.1049 0.724916)
			(stroke
				(width 0.1)
				(type default)
			)
			(layer "F.Fab")
		)
		(fp_line
			(start 1.1049 -0.724916)
			(end -1.1049 -0.724916)
			(stroke
				(width 0.1)
				(type default)
			)
			(layer "F.Fab")
		)
		(fp_line
			(start 1.1049 0.724916)
			(end 1.1049 -0.724916)
			(stroke
				(width 0.1)
				(type default)
			)
			(layer "F.Fab")
		)
		(pad "1" smd rect
			(at -0.889 0 180)
			(size 1.016 1.27)
			(layers "F.Cu" "F.Mask" "F.Paste")
			(net "PVCCIN_CPU0")
		)
		(pad "2" smd rect
			(at 0.889 0 180)
			(size 1.016 1.27)
			(layers "F.Cu" "F.Mask" "F.Paste")
			(net "GND")
		)
	)
	(footprint ""
		(layer "F.Cu")
		(at 76.881736 -142.587218 -90)
		(property "Reference" "R675"
			(at 0 0 270)
			(layer "F.SilkS")
			(hide yes)
			(effects
				(font
					(size 1.27 1.27)
				)
			)
		)
		(property "Value" ""
			(at 0 0 270)
			(layer "F.Fab")
			(effects
				(font
					(size 1.27 1.27)
				)
			)
		)
		(duplicate_pad_numbers_are_jumpers no)
		(fp_line
			(start -0.7874 0.4064)
			(end -0.7874 -0.4064)
			(stroke
				(width 0.1524)
				(type default)
			)
			(layer "F.SilkS")
		)
		(fp_line
			(start 0.7874 0.4064)
			(end -0.7874 0.4064)
			(stroke
				(width 0.1524)
				(type default)
			)
			(layer "F.SilkS")
		)
		(fp_line
			(start -0.7874 -0.4064)
			(end 0.7874 -0.4064)
			(stroke
				(width 0.1524)
				(type default)
			)
			(layer "F.SilkS")
		)
		(fp_line
			(start 0.7874 -0.4064)
			(end 0.7874 0.4064)
			(stroke
				(width 0.1524)
				(type default)
			)
			(layer "F.SilkS")
		)
		(fp_line
			(start -0.67945 0.3048)
			(end -0.67945 -0.305054)
			(stroke
				(width 0.1)
				(type default)
			)
			(layer "F.Fab")
		)
		(fp_line
			(start -0.12065 0.3048)
			(end -0.67945 0.3048)
			(stroke
				(width 0.1)
				(type default)
			)
			(layer "F.Fab")
		)
		(fp_line
			(start 0.120396 0.3048)
			(end 0.120396 0.2794)
			(stroke
				(width 0.1)
				(type default)
			)
			(layer "F.Fab")
		)
		(fp_line
			(start 0.67945 0.3048)
			(end 0.120396 0.3048)
			(stroke
				(width 0.1)
				(type default)
			)
			(layer "F.Fab")
		)
		(fp_line
			(start -0.12065 0.2794)
			(end -0.12065 0.3048)
			(stroke
				(width 0.1)
				(type default)
			)
			(layer "F.Fab")
		)
		(fp_line
			(start 0.120396 0.2794)
			(end -0.12065 0.2794)
			(stroke
				(width 0.1)
				(type default)
			)
			(layer "F.Fab")
		)
		(fp_line
			(start -0.12065 -0.2794)
			(end 0.12065 -0.2794)
			(stroke
				(width 0.1)
				(type default)
			)
			(layer "F.Fab")
		)
		(fp_line
			(start 0.12065 -0.2794)
			(end 0.12065 -0.3048)
			(stroke
				(width 0.1)
				(type default)
			)
			(layer "F.Fab")
		)
		(fp_line
			(start 0.12065 -0.3048)
			(end 0.67945 -0.3048)
			(stroke
				(width 0.1)
				(type default)
			)
			(layer "F.Fab")
		)
		(fp_line
			(start 0.67945 -0.3048)
			(end 0.67945 0.3048)
			(stroke
				(width 0.1)
				(type default)
			)
			(layer "F.Fab")
		)
		(fp_line
			(start -0.67945 -0.305054)
			(end -0.12065 -0.305054)
			(stroke
				(width 0.1)
				(type default)
			)
			(layer "F.Fab")
		)
		(fp_line
			(start -0.12065 -0.305054)
			(end -0.12065 -0.2794)
			(stroke
				(width 0.1)
				(type default)
			)
			(layer "F.Fab")
		)
		(pad "1" smd circle
			(at -0.40005 0 270)
			(size 0 0)
			(layers "F.Cu" "F.Mask" "F.Paste")
			(net "I3C_SPD_DDRABCD_CPU1_LVC1_R_SDA")
		)
		(pad "2" smd circle
			(at 0.40005 0 270)
			(size 0 0)
			(layers "F.Cu" "F.Mask" "F.Paste")
			(net "I3C_SPD_DDRABCD_CPU1_LVC1_SDA")
		)
	)
	(footprint ""
		(layer "F.Cu")
		(at 348.961964 -66.074544)
		(property "Reference" "C145"
			(at 0 0 0)
			(layer "F.SilkS")
			(hide yes)
			(effects
				(font
					(size 1.27 1.27)
				)
			)
		)
		(property "Value" ""
			(at 0 0 0)
			(layer "F.Fab")
			(effects
				(font
					(size 1.27 1.27)
				)
			)
		)
		(duplicate_pad_numbers_are_jumpers no)
		(fp_line
			(start -0.299974 -0.150114)
			(end 0.299974 -0.150114)
			(stroke
				(width 0.1)
				(type default)
			)
			(layer "F.Fab")
		)
		(fp_line
			(start -0.299974 0.150114)
			(end -0.299974 -0.150114)
			(stroke
				(width 0.1)
				(type default)
			)
			(layer "F.Fab")
		)
		(fp_line
			(start 0.299974 -0.150114)
			(end 0.299974 0.150114)
			(stroke
				(width 0.1)
				(type default)
			)
			(layer "F.Fab")
		)
		(fp_line
			(start 0.299974 0.150114)
			(end -0.299974 0.150114)
			(stroke
				(width 0.1)
				(type default)
			)
			(layer "F.Fab")
		)
		(pad "1" smd rect
			(at -0.2667 0)
			(size 0.3048 0.381)
			(layers "F.Cu" "F.Mask" "F.Paste")
			(net "DMI_CPU0_PCH_TX_C_DN<4>")
		)
		(pad "2" smd rect
			(at 0.2667 0)
			(size 0.3048 0.381)
			(layers "F.Cu" "F.Mask" "F.Paste")
			(net "DMI_CPU0_PCH_TX_DN<4>")
		)
		(zone
			(layer "In1.Cu")
			(hatch none 0.5)
			(connect_pads
				(clearance 0)
			)
			(min_thickness 0.25)
			(keepout
				(tracks not_allowed)
				(vias allowed)
				(pads allowed)
				(copperpour not_allowed)
				(footprints allowed)
			)
			(placement
				(enabled no)
				(sheetname "")
			)
			(fill
				(thermal_gap 0.5)
				(thermal_bridge_width 0.5)
				(island_removal_mode 0)
			)
			(polygon
				(pts
					(arc
						(start 348.568264 -65.833244)
						(mid 348.514382 -65.855562)
						(end 348.492064 -65.909444)
					)
					(arc
						(start 348.492064 -66.239644)
						(mid 348.514382 -66.293526)
						(end 348.568264 -66.315844)
					)
					(arc
						(start 348.822264 -66.315844)
						(mid 348.876146 -66.293526)
						(end 348.898464 -66.239644)
					)
					(arc
						(start 348.898464 -65.909444)
						(mid 348.876146 -65.855562)
						(end 348.822264 -65.833244)
					)
				)
			)
		)
		(zone
			(layer "In1.Cu")
			(hatch none 0.5)
			(connect_pads
				(clearance 0)
			)
			(min_thickness 0.25)
			(keepout
				(tracks not_allowed)
				(vias allowed)
				(pads allowed)
				(copperpour not_allowed)
				(footprints allowed)
			)
			(placement
				(enabled no)
				(sheetname "")
			)
			(fill
				(thermal_gap 0.5)
				(thermal_bridge_width 0.5)
				(island_removal_mode 0)
			)
			(polygon
				(pts
					(arc
						(start 349.101664 -65.833244)
						(mid 349.047782 -65.855562)
						(end 349.025464 -65.909444)
					)
					(arc
						(start 349.025464 -66.239644)
						(mid 349.047782 -66.293526)
						(end 349.101664 -66.315844)
					)
					(arc
						(start 349.355664 -66.315844)
						(mid 349.409546 -66.293526)
						(end 349.431864 -66.239644)
					)
					(arc
						(start 349.431864 -65.909444)
						(mid 349.409546 -65.855562)
						(end 349.355664 -65.833244)
					)
				)
			)
		)
	)
)
